G04 ================== begin FILE IDENTIFICATION RECORD ==================*
G04 Layout Name:  14629-1a.brd*
G04 Film Name:    TMASK*
G04 File Format:  Gerber RS274X*
G04 File Origin:  Cadence Allegro 16.5-S037*
G04 Origin Date:  Tue Nov 25 11:50:42 2014*
G04 *
G04 Layer:  VIA CLASS/SOLDERMASK_TOP*
G04 Layer:  PIN/SOLDERMASK_TOP*
G04 Layer:  PACKAGE GEOMETRY/SOLDERMASK_TOP*
G04 Layer:  DRAWING FORMAT/LAYER_PCB_STORY*
G04 Layer:  DRAWING FORMAT/LAYER_SOLDER_T*
G04 Layer:  BOARD GEOMETRY/SOLDERMASK_TOP*
G04 *
G04 Offset:    (0.00 0.00)*
G04 Mirror:    No*
G04 Mode:      Positive*
G04 Rotation:  0*
G04 FullContactRelief:  No*
G04 UndefLineWidth:     6.00*
G04 ================== end FILE IDENTIFICATION RECORD ====================*
%FSLAX35Y35*MOIN*%
%IR0*IPPOS*OFA0.00000B0.00000*MIA0B0*SFA1.00000B1.00000*%
%AMMACRO17*
4,1,40,.017,-.013,
.017,.013,
.016939,.013695,
.016759,.014368,
.016464,.015,
.016064,.015571,
.015571,.016064,
.015,.016464,
.014368,.016759,
.013695,.016939,
.013,.017,
-.013,.017,
-.013695,.016939,
-.014368,.016759,
-.015,.016464,
-.015571,.016064,
-.016064,.015571,
-.016464,.015,
-.016759,.014368,
-.016939,.013695,
-.017,.013,
-.017,-.013,
-.016939,-.013695,
-.016759,-.014368,
-.016464,-.015,
-.016064,-.015571,
-.015571,-.016064,
-.015,-.016464,
-.014368,-.016759,
-.013695,-.016939,
-.013,-.017,
.013,-.017,
.013695,-.016939,
.014368,-.016759,
.015,-.016464,
.015571,-.016064,
.016064,-.015571,
.016464,-.015,
.016759,-.014368,
.016939,-.013695,
.017,-.013,
0.0*
%
%ADD17MACRO17*%
%ADD35R,.11X.055*%
%ADD42R,.074X.122*%
%AMMACRO11*
4,1,21,.062,.1775,
.092823,.174803,
.122709,.166795,
.15075,.15372,
.176095,.135973,
.197973,.114095,
.21572,.08875,
.228795,.060709,
.236803,.030823,
.2395,0.0,
.236803,-.030823,
.228795,-.060709,
.21572,-.08875,
.197973,-.114095,
.176095,-.135973,
.15075,-.15372,
.122709,-.166795,
.092823,-.174803,
.062,-.1775,
-.2395,-.1775,
-.2395,.1775,
.062,.1775,
0.0*
%
%ADD11MACRO11*%
%ADD33C,.032*%
%ADD40C,.052*%
%ADD15R,.197X.032*%
%ADD12C,.08*%
%ADD39C,.064*%
%ADD29C,.028*%
%ADD37C,.057*%
%ADD10C,.086*%
%AMMACRO32*
4,1,40,.007,.011,
-.007,.011,
-.007695,.010939,
-.008368,.010759,
-.009,.010464,
-.009571,.010064,
-.010064,.009571,
-.010464,.009,
-.010759,.008368,
-.010939,.007695,
-.011,.007,
-.011,-.007,
-.010939,-.007695,
-.010759,-.008368,
-.010464,-.009,
-.010064,-.009571,
-.009571,-.010064,
-.009,-.010464,
-.008368,-.010759,
-.007695,-.010939,
-.007,-.011,
.007,-.011,
.007695,-.010939,
.008368,-.010759,
.009,-.010464,
.009571,-.010064,
.010064,-.009571,
.010464,-.009,
.010759,-.008368,
.010939,-.007695,
.011,-.007,
.011,.007,
.010939,.007695,
.010759,.008368,
.010464,.009,
.010064,.009571,
.009571,.010064,
.009,.010464,
.008368,.010759,
.007695,.010939,
.007,.011,
0.0*
%
%ADD32MACRO32*%
%AMMACRO28*
4,1,40,.011,-.007,
.011,.007,
.010939,.007695,
.010759,.008368,
.010464,.009,
.010064,.009571,
.009571,.010064,
.009,.010464,
.008368,.010759,
.007695,.010939,
.007,.011,
-.007,.011,
-.007695,.010939,
-.008368,.010759,
-.009,.010464,
-.009571,.010064,
-.010064,.009571,
-.010464,.009,
-.010759,.008368,
-.010939,.007695,
-.011,.007,
-.011,-.007,
-.010939,-.007695,
-.010759,-.008368,
-.010464,-.009,
-.010064,-.009571,
-.009571,-.010064,
-.009,-.010464,
-.008368,-.010759,
-.007695,-.010939,
-.007,-.011,
.007,-.011,
.007695,-.010939,
.008368,-.010759,
.009,-.010464,
.009571,-.010064,
.010064,-.009571,
.010464,-.009,
.010759,-.008368,
.010939,-.007695,
.011,-.007,
0.0*
%
%ADD28MACRO28*%
%AMMACRO25*
4,1,40,-.017,.013,
-.017,-.013,
-.016939,-.013695,
-.016759,-.014368,
-.016464,-.015,
-.016064,-.015571,
-.015571,-.016064,
-.015,-.016464,
-.014368,-.016759,
-.013695,-.016939,
-.013,-.017,
.013,-.017,
.013695,-.016939,
.014368,-.016759,
.015,-.016464,
.015571,-.016064,
.016064,-.015571,
.016464,-.015,
.016759,-.014368,
.016939,-.013695,
.017,-.013,
.017,.013,
.016939,.013695,
.016759,.014368,
.016464,.015,
.016064,.015571,
.015571,.016064,
.015,.016464,
.014368,.016759,
.013695,.016939,
.013,.017,
-.013,.017,
-.013695,.016939,
-.014368,.016759,
-.015,.016464,
-.015571,.016064,
-.016064,.015571,
-.016464,.015,
-.016759,.014368,
-.016939,.013695,
-.017,.013,
0.0*
%
%ADD25MACRO25*%
%AMMACRO31*
4,1,40,.007,.011,
-.007,.011,
-.007695,.010939,
-.008368,.010759,
-.009,.010464,
-.009571,.010064,
-.010064,.009571,
-.010464,.009,
-.010759,.008368,
-.010939,.007695,
-.011,.007,
-.011,-.007,
-.010939,-.007695,
-.010759,-.008368,
-.010464,-.009,
-.010064,-.009571,
-.009571,-.010064,
-.009,-.010464,
-.008368,-.010759,
-.007695,-.010939,
-.007,-.011,
.007,-.011,
.007695,-.010939,
.008368,-.010759,
.009,-.010464,
.009571,-.010064,
.010064,-.009571,
.010464,-.009,
.010759,-.008368,
.010939,-.007695,
.011,-.007,
.011,.007,
.010939,.007695,
.010759,.008368,
.010464,.009,
.010064,.009571,
.009571,.010064,
.009,.010464,
.008368,.010759,
.007695,.010939,
.007,.011,
0.0*
%
%ADD31MACRO31*%
%AMMACRO21*
4,1,40,.011,-.007,
.011,.007,
.010939,.007695,
.010759,.008368,
.010464,.009,
.010064,.009571,
.009571,.010064,
.009,.010464,
.008368,.010759,
.007695,.010939,
.007,.011,
-.007,.011,
-.007695,.010939,
-.008368,.010759,
-.009,.010464,
-.009571,.010064,
-.010064,.009571,
-.010464,.009,
-.010759,.008368,
-.010939,.007695,
-.011,.007,
-.011,-.007,
-.010939,-.007695,
-.010759,-.008368,
-.010464,-.009,
-.010064,-.009571,
-.009571,-.010064,
-.009,-.010464,
-.008368,-.010759,
-.007695,-.010939,
-.007,-.011,
.007,-.011,
.007695,-.010939,
.008368,-.010759,
.009,-.010464,
.009571,-.010064,
.010064,-.009571,
.010464,-.009,
.010759,-.008368,
.010939,-.007695,
.011,-.007,
0.0*
%
%ADD21MACRO21*%
%AMMACRO18*
4,1,40,-.017,.013,
-.017,-.013,
-.016939,-.013695,
-.016759,-.014368,
-.016464,-.015,
-.016064,-.015571,
-.015571,-.016064,
-.015,-.016464,
-.014368,-.016759,
-.013695,-.016939,
-.013,-.017,
.013,-.017,
.013695,-.016939,
.014368,-.016759,
.015,-.016464,
.015571,-.016064,
.016064,-.015571,
.016464,-.015,
.016759,-.014368,
.016939,-.013695,
.017,-.013,
.017,.013,
.016939,.013695,
.016759,.014368,
.016464,.015,
.016064,.015571,
.015571,.016064,
.015,.016464,
.014368,.016759,
.013695,.016939,
.013,.017,
-.013,.017,
-.013695,.016939,
-.014368,.016759,
-.015,.016464,
-.015571,.016064,
-.016064,.015571,
-.016464,.015,
-.016759,.014368,
-.016939,.013695,
-.017,.013,
0.0*
%
%ADD18MACRO18*%
%ADD23R,.016X.06*%
%ADD14R,.055X.045*%
%ADD16R,.248X.165*%
%ADD13R,.248X.372*%
%ADD41C,.158*%
%ADD34O,.827X.355*%
%AMMACRO38*
4,1,40,.007,.0225,
.008389,.022378,
.009736,.022018,
.011,.021428,
.012142,.020628,
.013128,.019642,
.013928,.0185,
.014518,.017236,
.014878,.015889,
.015,.0145,
.015,-.0145,
.014878,-.015889,
.014518,-.017236,
.013928,-.0185,
.013128,-.019642,
.012142,-.020628,
.011,-.021428,
.009736,-.022018,
.008389,-.022378,
.007,-.0225,
-.007,-.0225,
-.008389,-.022378,
-.009736,-.022018,
-.011,-.021428,
-.012142,-.020628,
-.013128,-.019642,
-.013928,-.0185,
-.014518,-.017236,
-.014878,-.015889,
-.015,-.0145,
-.015,.0145,
-.014878,.015889,
-.014518,.017236,
-.013928,.0185,
-.013128,.019642,
-.012142,.020628,
-.011,.021428,
-.009736,.022018,
-.008389,.022378,
-.007,.0225,
.007,.0225,
0.0*
%
%ADD38MACRO38*%
%ADD36R,.095X.09*%
%AMMACRO30*
4,1,40,-.008,-.012,
.008,-.012,
.008695,-.011939,
.009368,-.011759,
.01,-.011464,
.010571,-.011064,
.011064,-.010571,
.011464,-.01,
.011759,-.009368,
.011939,-.008695,
.012,-.008,
.012,.008,
.011939,.008695,
.011759,.009368,
.011464,.01,
.011064,.010571,
.010571,.011064,
.01,.011464,
.009368,.011759,
.008695,.011939,
.008,.012,
-.008,.012,
-.008695,.011939,
-.009368,.011759,
-.01,.011464,
-.010571,.011064,
-.011064,.010571,
-.011464,.01,
-.011759,.009368,
-.011939,.008695,
-.012,.008,
-.012,-.008,
-.011939,-.008695,
-.011759,-.009368,
-.011464,-.01,
-.011064,-.010571,
-.010571,-.011064,
-.01,-.011464,
-.009368,-.011759,
-.008695,-.011939,
-.008,-.012,
0.0*
%
%ADD30MACRO30*%
%AMMACRO27*
4,1,40,-.007,-.011,
.007,-.011,
.007695,-.010939,
.008368,-.010759,
.009,-.010464,
.009571,-.010064,
.010064,-.009571,
.010464,-.009,
.010759,-.008368,
.010939,-.007695,
.011,-.007,
.011,.007,
.010939,.007695,
.010759,.008368,
.010464,.009,
.010064,.009571,
.009571,.010064,
.009,.010464,
.008368,.010759,
.007695,.010939,
.007,.011,
-.007,.011,
-.007695,.010939,
-.008368,.010759,
-.009,.010464,
-.009571,.010064,
-.010064,.009571,
-.010464,.009,
-.010759,.008368,
-.010939,.007695,
-.011,.007,
-.011,-.007,
-.010939,-.007695,
-.010759,-.008368,
-.010464,-.009,
-.010064,-.009571,
-.009571,-.010064,
-.009,-.010464,
-.008368,-.010759,
-.007695,-.010939,
-.007,-.011,
0.0*
%
%ADD27MACRO27*%
%AMMACRO26*
4,1,40,-.011,.007,
-.011,-.007,
-.010939,-.007695,
-.010759,-.008368,
-.010464,-.009,
-.010064,-.009571,
-.009571,-.010064,
-.009,-.010464,
-.008368,-.010759,
-.007695,-.010939,
-.007,-.011,
.007,-.011,
.007695,-.010939,
.008368,-.010759,
.009,-.010464,
.009571,-.010064,
.010064,-.009571,
.010464,-.009,
.010759,-.008368,
.010939,-.007695,
.011,-.007,
.011,.007,
.010939,.007695,
.010759,.008368,
.010464,.009,
.010064,.009571,
.009571,.010064,
.009,.010464,
.008368,.010759,
.007695,.010939,
.007,.011,
-.007,.011,
-.007695,.010939,
-.008368,.010759,
-.009,.010464,
-.009571,.010064,
-.010064,.009571,
-.010464,.009,
-.010759,.008368,
-.010939,.007695,
-.011,.007,
0.0*
%
%ADD26MACRO26*%
%AMMACRO24*
4,1,40,.017,-.013,
.017,.013,
.016939,.013695,
.016759,.014368,
.016464,.015,
.016064,.015571,
.015571,.016064,
.015,.016464,
.014368,.016759,
.013695,.016939,
.013,.017,
-.013,.017,
-.013695,.016939,
-.014368,.016759,
-.015,.016464,
-.015571,.016064,
-.016064,.015571,
-.016464,.015,
-.016759,.014368,
-.016939,.013695,
-.017,.013,
-.017,-.013,
-.016939,-.013695,
-.016759,-.014368,
-.016464,-.015,
-.016064,-.015571,
-.015571,-.016064,
-.015,-.016464,
-.014368,-.016759,
-.013695,-.016939,
-.013,-.017,
.013,-.017,
.013695,-.016939,
.014368,-.016759,
.015,-.016464,
.015571,-.016064,
.016064,-.015571,
.016464,-.015,
.016759,-.014368,
.016939,-.013695,
.017,-.013,
0.0*
%
%ADD24MACRO24*%
%AMMACRO20*
4,1,40,-.007,-.011,
.007,-.011,
.007695,-.010939,
.008368,-.010759,
.009,-.010464,
.009571,-.010064,
.010064,-.009571,
.010464,-.009,
.010759,-.008368,
.010939,-.007695,
.011,-.007,
.011,.007,
.010939,.007695,
.010759,.008368,
.010464,.009,
.010064,.009571,
.009571,.010064,
.009,.010464,
.008368,.010759,
.007695,.010939,
.007,.011,
-.007,.011,
-.007695,.010939,
-.008368,.010759,
-.009,.010464,
-.009571,.010064,
-.010064,.009571,
-.010464,.009,
-.010759,.008368,
-.010939,.007695,
-.011,.007,
-.011,-.007,
-.010939,-.007695,
-.010759,-.008368,
-.010464,-.009,
-.010064,-.009571,
-.009571,-.010064,
-.009,-.010464,
-.008368,-.010759,
-.007695,-.010939,
-.007,-.011,
0.0*
%
%ADD20MACRO20*%
%AMMACRO19*
4,1,40,-.008,-.012,
.008,-.012,
.008695,-.011939,
.009368,-.011759,
.01,-.011464,
.010571,-.011064,
.011064,-.010571,
.011464,-.01,
.011759,-.009368,
.011939,-.008695,
.012,-.008,
.012,.008,
.011939,.008695,
.011759,.009368,
.011464,.01,
.011064,.010571,
.010571,.011064,
.01,.011464,
.009368,.011759,
.008695,.011939,
.008,.012,
-.008,.012,
-.008695,.011939,
-.009368,.011759,
-.01,.011464,
-.010571,.011064,
-.011064,.010571,
-.011464,.01,
-.011759,.009368,
-.011939,.008695,
-.012,.008,
-.012,-.008,
-.011939,-.008695,
-.011759,-.009368,
-.011464,-.01,
-.011064,-.010571,
-.010571,-.011064,
-.01,-.011464,
-.009368,-.011759,
-.008695,-.011939,
-.008,-.012,
0.0*
%
%ADD19MACRO19*%
%AMMACRO22*
4,1,40,-.011,.007,
-.011,-.007,
-.010939,-.007695,
-.010759,-.008368,
-.010464,-.009,
-.010064,-.009571,
-.009571,-.010064,
-.009,-.010464,
-.008368,-.010759,
-.007695,-.010939,
-.007,-.011,
.007,-.011,
.007695,-.010939,
.008368,-.010759,
.009,-.010464,
.009571,-.010064,
.010064,-.009571,
.010464,-.009,
.010759,-.008368,
.010939,-.007695,
.011,-.007,
.011,.007,
.010939,.007695,
.010759,.008368,
.010464,.009,
.010064,.009571,
.009571,.010064,
.009,.010464,
.008368,.010759,
.007695,.010939,
.007,.011,
-.007,.011,
-.007695,.010939,
-.008368,.010759,
-.009,.010464,
-.009571,.010064,
-.010064,.009571,
-.010464,.009,
-.010759,.008368,
-.010939,.007695,
-.011,.007,
0.0*
%
%ADD22MACRO22*%
%ADD43C,.02*%
%ADD44C,.006*%
G75*
%LPD*%
G75*
G36*
G01X-43611Y110602D02*
X-12605D01*
Y291274D01*
X-17705D01*
Y366242D01*
X-43611D01*
Y110602D01*
G37*
G54D10*
X-23621Y15748D03*
Y937008D03*
X1312285Y15747D03*
X1312281Y889328D03*
G54D20*
X35198Y333436D03*
Y337936D03*
X30108Y368932D03*
Y374132D03*
X66098Y369470D03*
X66147Y373979D03*
X66150Y378236D03*
X534333Y268971D03*
Y263971D03*
X530236Y322102D03*
X530136Y330602D03*
X530236Y326402D03*
X522800Y326000D03*
G54D11*
X23957Y61023D03*
Y415354D03*
G54D30*
X41309Y391063D03*
G54D21*
X52705Y352395D03*
X48325Y352450D03*
X57398Y352460D03*
G54D12*
X-23622Y62794D03*
Y916269D03*
X1297695Y58466D03*
G54D22*
X43159Y377285D03*
X43072Y369247D03*
X51094Y390725D03*
X60052Y390692D03*
X55352Y390774D03*
X538000Y296700D03*
X548000Y432700D03*
G54D13*
X-25005Y173422D03*
Y133422D03*
Y213422D03*
Y253422D03*
G54D31*
X69491Y365163D03*
X526200Y322000D03*
X533536Y334902D03*
X547700Y419000D03*
G54D40*
X571496Y433071D03*
X581339D03*
X591182D03*
G54D41*
X600709Y136909D03*
Y311909D03*
G54D14*
X197Y189819D03*
Y197419D03*
X9297Y189819D03*
Y197419D03*
X472898Y182636D03*
Y190236D03*
X550498Y322336D03*
Y329936D03*
G54D23*
X49902Y379652D03*
X52462D03*
X55022D03*
X57582D03*
Y363352D03*
X55022D03*
X52462D03*
X49902D03*
G54D32*
X66091Y365163D03*
X522800Y322000D03*
X530136Y334902D03*
X544300Y419000D03*
G54D24*
X38128Y379932D03*
X45807Y393668D03*
X542500Y274771D03*
X634488Y77603D03*
G54D15*
X-27555Y332202D03*
Y327202D03*
Y322202D03*
Y317202D03*
Y312202D03*
Y307202D03*
Y302202D03*
Y357202D03*
Y352202D03*
Y347202D03*
Y342202D03*
Y337202D03*
G54D33*
X67408Y391259D03*
G54D42*
X607104Y387500D03*
X618566D03*
Y343800D03*
X607104D03*
G54D43*
G01X-4246Y-109426D02*
Y-189426D01*
G01D02*
X1290354D01*
G01X-4246Y-144926D02*
X1290354D01*
G01X-8246Y-93426D02*
G02I-12000J0D01*
G01X-13396D02*
G02I-6850J0D01*
G01X-20246Y-109426D02*
Y-77426D01*
G01X-4246Y-93426D02*
X-36246D01*
G01X-4246Y-109426D02*
X1290354D01*
G01X502854D02*
Y-189426D01*
G01X640354Y-109426D02*
Y-189426D01*
G01X755354Y-109426D02*
Y-189426D01*
G01X922854Y-109426D02*
Y-189426D01*
G01X1092854Y-109426D02*
Y-189426D01*
G01X1290354Y-109426D02*
Y-189426D01*
G01X1318354Y-93426D02*
G02I-12000J0D01*
G01X1313204D02*
G02I-6850J0D01*
G01X1306354Y-109426D02*
Y-77426D01*
G01X1322354Y-93426D02*
X1290354D01*
G54D34*
X475061Y23622D03*
X494746Y448818D03*
G54D16*
X-25005Y283072D03*
G54D25*
X38109Y363133D03*
X542500Y258171D03*
X618000Y71700D03*
X617798Y403136D03*
X612798Y403036D03*
G54D44*
G01X121969Y-179426D02*
Y-161926D01*
G01X131139D02*
Y-179426D01*
G01Y-170676D02*
X121969D01*
G01X144054Y-179426D02*
X142744Y-179134D01*
X141434Y-177968D01*
X140560Y-175926D01*
X140124Y-173593D01*
X140560Y-171259D01*
X141434Y-169218D01*
X142744Y-168051D01*
X144054Y-167760D01*
X145364Y-168051D01*
X146674Y-169218D01*
X147547Y-171259D01*
X147766Y-173593D01*
X147547Y-175926D01*
X146674Y-177968D01*
X145364Y-179134D01*
X144054Y-179426D01*
G01X157842D02*
Y-167760D01*
G01Y-170676D02*
X158716Y-169218D01*
X160026Y-168051D01*
X161772Y-167760D01*
X163300Y-168051D01*
X164611Y-169218D01*
X165266Y-171259D01*
Y-179426D01*
G01X175779Y-171551D02*
X182766D01*
X182111Y-169509D01*
X181019Y-168343D01*
X179491Y-167760D01*
X177962Y-168051D01*
X176652Y-168926D01*
X175779Y-170968D01*
X175342Y-172718D01*
Y-174468D01*
X175779Y-176218D01*
X176871Y-177968D01*
X178181Y-179134D01*
X179709Y-179426D01*
X181237Y-178843D01*
X182766Y-177093D01*
G01X191969Y-184676D02*
X193279Y-185259D01*
X195026Y-184676D01*
X196117Y-183510D01*
X196991Y-182051D01*
X198300Y-177385D01*
X201139Y-167760D01*
G01X194152D02*
X198300Y-177385D01*
G01X233300Y-170093D02*
X234174Y-169218D01*
X234829Y-167760D01*
X235266Y-165717D01*
X234829Y-163968D01*
X233956Y-162801D01*
X232427Y-161926D01*
X226532D01*
Y-179426D01*
X233737D01*
X235266Y-178260D01*
X236139Y-176509D01*
X236576Y-174468D01*
X236139Y-172426D01*
X234829Y-170676D01*
X233300Y-170093D01*
X226532D01*
G01X252984Y-179426D02*
Y-167760D01*
G01Y-169801D02*
X252111Y-168635D01*
X250800Y-168051D01*
X249272Y-167760D01*
X247744Y-168343D01*
X246434Y-169509D01*
X245560Y-171259D01*
X245124Y-173593D01*
X245560Y-175926D01*
X246434Y-177676D01*
X247744Y-178843D01*
X249272Y-179426D01*
X250800Y-179134D01*
X252111Y-178260D01*
X252984Y-177093D01*
G01X270484Y-161926D02*
Y-179426D01*
G01Y-176802D02*
X269611Y-178260D01*
X268300Y-179134D01*
X266772Y-179426D01*
X265026Y-178843D01*
X263716Y-177385D01*
X262842Y-175635D01*
X262624Y-173593D01*
X262842Y-171551D01*
X263716Y-169801D01*
X265026Y-168343D01*
X266772Y-167760D01*
X268300Y-168051D01*
X269392Y-168635D01*
X270484Y-169801D01*
G01X280997Y-183801D02*
X282526Y-184968D01*
X284272Y-185259D01*
X285800Y-184968D01*
X287111Y-183510D01*
X287984Y-181468D01*
Y-167760D01*
G01Y-170093D02*
X287111Y-168926D01*
X285800Y-168051D01*
X284272Y-167760D01*
X282526Y-168343D01*
X281434Y-169509D01*
X280560Y-171551D01*
X280124Y-173593D01*
X280342Y-175343D01*
X281216Y-177385D01*
X282526Y-178843D01*
X284272Y-179426D01*
X285582Y-179134D01*
X287111Y-177968D01*
X287984Y-176802D01*
G01X298279Y-171551D02*
X305266D01*
X304611Y-169509D01*
X303519Y-168343D01*
X301991Y-167760D01*
X300462Y-168051D01*
X299152Y-168926D01*
X298279Y-170968D01*
X297842Y-172718D01*
Y-174468D01*
X298279Y-176218D01*
X299371Y-177968D01*
X300681Y-179134D01*
X302209Y-179426D01*
X303737Y-178843D01*
X305266Y-177093D01*
G01X315997Y-179426D02*
Y-167760D01*
G01Y-170093D02*
X317089Y-168926D01*
X318181Y-168051D01*
X319709Y-167760D01*
X320800Y-168051D01*
X322111Y-168926D01*
G01X349687Y-179426D02*
Y-161926D01*
X354927D01*
X356674Y-162801D01*
X357984Y-164843D01*
X358421Y-167176D01*
X357984Y-169509D01*
X356892Y-171259D01*
X354927Y-172135D01*
X349687D01*
G01X371554Y-161926D02*
Y-179426D01*
G01X366532Y-161926D02*
X376576D01*
G01X390800Y-170093D02*
X391674Y-169218D01*
X392329Y-167760D01*
X392766Y-165717D01*
X392329Y-163968D01*
X391456Y-162801D01*
X389927Y-161926D01*
X384032D01*
Y-179426D01*
X391237D01*
X392766Y-178260D01*
X393639Y-176509D01*
X394076Y-174468D01*
X393639Y-172426D01*
X392329Y-170676D01*
X390800Y-170093D01*
X384032D01*
G01X208377Y-134426D02*
Y-116926D01*
X214054Y-131509D01*
X219731Y-116926D01*
Y-134426D01*
G01X231554D02*
X230244Y-134134D01*
X228934Y-132968D01*
X228060Y-130926D01*
X227624Y-128593D01*
X228060Y-126259D01*
X228934Y-124218D01*
X230244Y-123051D01*
X231554Y-122760D01*
X232864Y-123051D01*
X234174Y-124218D01*
X235047Y-126259D01*
X235266Y-128593D01*
X235047Y-130926D01*
X234174Y-132968D01*
X232864Y-134134D01*
X231554Y-134426D01*
G01X252984Y-116926D02*
Y-134426D01*
G01Y-131802D02*
X252111Y-133260D01*
X250800Y-134134D01*
X249272Y-134426D01*
X247526Y-133843D01*
X246216Y-132385D01*
X245342Y-130635D01*
X245124Y-128593D01*
X245342Y-126551D01*
X246216Y-124801D01*
X247526Y-123343D01*
X249272Y-122760D01*
X250800Y-123051D01*
X251892Y-123635D01*
X252984Y-124801D01*
G01X263279Y-126551D02*
X270266D01*
X269611Y-124509D01*
X268519Y-123343D01*
X266991Y-122760D01*
X265462Y-123051D01*
X264152Y-123926D01*
X263279Y-125968D01*
X262842Y-127718D01*
Y-129468D01*
X263279Y-131218D01*
X264371Y-132968D01*
X265681Y-134134D01*
X267209Y-134426D01*
X268737Y-133843D01*
X270266Y-132093D01*
G01X284054Y-134426D02*
Y-116926D01*
G01X536554Y-179426D02*
Y-161926D01*
X533934Y-165426D01*
G01Y-179426D02*
X539174D01*
G01X556674D02*
Y-161926D01*
X548595Y-174468D01*
X559513D01*
G01X567406Y-172135D02*
X568934Y-170093D01*
X570244Y-168926D01*
X571991Y-168343D01*
X573519Y-168926D01*
X574611Y-170093D01*
X575484Y-171843D01*
X575702Y-173884D01*
X575484Y-175635D01*
X574611Y-177385D01*
X573300Y-178843D01*
X571772Y-179426D01*
X570026Y-178843D01*
X568497Y-177093D01*
X567624Y-174468D01*
X567406Y-171551D01*
X567842Y-167760D01*
X568497Y-165717D01*
X569589Y-163676D01*
X571117Y-162218D01*
X572646Y-161926D01*
X574174Y-162509D01*
X575266Y-163968D01*
G01X584906Y-164843D02*
X586216Y-163093D01*
X587744Y-162218D01*
X589491Y-161926D01*
X591674Y-162509D01*
X593202Y-163968D01*
X593639Y-165717D01*
X593421Y-167468D01*
X592547Y-168926D01*
X588181Y-171843D01*
X586216Y-173884D01*
X584906Y-176802D01*
X584469Y-179426D01*
X593639D01*
G01X602842Y-177385D02*
X604371Y-178843D01*
X606117Y-179426D01*
X607864Y-178843D01*
X609392Y-177093D01*
X610484Y-174468D01*
X610921Y-171843D01*
Y-168635D01*
X610484Y-166010D01*
X609392Y-163676D01*
X608082Y-162509D01*
X606554Y-161926D01*
X604807Y-162509D01*
X603497Y-163676D01*
X602624Y-165426D01*
X602187Y-167760D01*
X602624Y-169801D01*
X603716Y-171843D01*
X605026Y-173010D01*
X606554Y-173301D01*
X608300Y-172718D01*
X609611Y-171259D01*
X610921Y-168635D01*
G01X523437Y-134426D02*
Y-116926D01*
X528677D01*
X530424Y-117801D01*
X531734Y-119843D01*
X532171Y-122176D01*
X531734Y-124509D01*
X530642Y-126259D01*
X528677Y-127135D01*
X523437D01*
G01X550107Y-118385D02*
X548797Y-117509D01*
X547269Y-116926D01*
X545522D01*
X543557Y-117801D01*
X542029Y-119259D01*
X540937Y-121010D01*
X540064Y-123926D01*
X539845Y-126551D01*
X540282Y-129176D01*
X540937Y-130926D01*
X542247Y-132676D01*
X543776Y-133843D01*
X545304Y-134426D01*
X546832D01*
X548361Y-133843D01*
X549671Y-132968D01*
X550763Y-131802D01*
G01X564550Y-125093D02*
X565424Y-124218D01*
X566079Y-122760D01*
X566516Y-120717D01*
X566079Y-118968D01*
X565206Y-117801D01*
X563677Y-116926D01*
X557782D01*
Y-134426D01*
X564987D01*
X566516Y-133260D01*
X567389Y-131509D01*
X567826Y-129468D01*
X567389Y-127426D01*
X566079Y-125676D01*
X564550Y-125093D01*
X557782D01*
G01X573754Y-140259D02*
X586854D01*
G01X592782Y-134426D02*
Y-116926D01*
X602826Y-134426D01*
Y-116926D01*
G01X615304Y-134426D02*
X613557Y-134134D01*
X612029Y-132968D01*
X610719Y-131218D01*
X609845Y-129176D01*
X609409Y-126843D01*
Y-124509D01*
X609845Y-122176D01*
X610719Y-120134D01*
X612029Y-118385D01*
X613557Y-117218D01*
X615304Y-116926D01*
X617050Y-117218D01*
X618579Y-118385D01*
X619889Y-120134D01*
X620763Y-122176D01*
X621199Y-124509D01*
Y-126843D01*
X620763Y-129176D01*
X619889Y-131218D01*
X618579Y-132968D01*
X617050Y-134134D01*
X615304Y-134426D01*
G01X689104Y-179426D02*
Y-161926D01*
X686484Y-165426D01*
G01Y-179426D02*
X691724D01*
G01X701145D02*
X706604Y-161926D01*
X712063Y-179426D01*
G01X710097Y-173301D02*
X703110D01*
G01X666145Y-116926D02*
X671604Y-134426D01*
X677063Y-116926D01*
G01X693471Y-134426D02*
X684737D01*
Y-116926D01*
X693471D01*
G01X689977Y-125384D02*
X684737D01*
G01X702237Y-134426D02*
Y-116926D01*
X707696D01*
X709442Y-117801D01*
X710534Y-118968D01*
X710971Y-121301D01*
X710534Y-123635D01*
X709224Y-125093D01*
X707696Y-125968D01*
X702237D01*
G01X707696D02*
X710971Y-134426D01*
G01X724104Y-135009D02*
X723667Y-134718D01*
Y-134134D01*
X724104Y-133843D01*
X724541Y-134134D01*
Y-134718D01*
X724104Y-135009D01*
G01X804054Y-161926D02*
Y-179426D01*
G01X799032Y-161926D02*
X809076D01*
G01X815877Y-179426D02*
Y-161926D01*
X821554Y-176509D01*
X827231Y-161926D01*
Y-179426D01*
G01X833595D02*
X839054Y-161926D01*
X844513Y-179426D01*
G01X842547Y-173301D02*
X835560D01*
G01X851969Y-177093D02*
X853716Y-178551D01*
X855681Y-179426D01*
X857427D01*
X859174Y-178551D01*
X860484Y-177093D01*
X861139Y-175051D01*
X860702Y-173010D01*
X859611Y-171259D01*
X857646Y-170093D01*
X855026Y-169509D01*
X853497Y-168343D01*
X852842Y-166301D01*
X853279Y-164259D01*
X854371Y-162801D01*
X855899Y-161926D01*
X857427D01*
X858956Y-162509D01*
X860266Y-163968D01*
G01X869251Y-179426D02*
Y-161926D01*
G01X877547D02*
X869251Y-172718D01*
G01X878857Y-179426D02*
X872962Y-167760D01*
G01X790937Y-116926D02*
Y-134426D01*
X799671D01*
G01X816734D02*
Y-122760D01*
G01Y-124801D02*
X815861Y-123635D01*
X814550Y-123051D01*
X813022Y-122760D01*
X811494Y-123343D01*
X810184Y-124509D01*
X809310Y-126259D01*
X808874Y-128593D01*
X809310Y-130926D01*
X810184Y-132676D01*
X811494Y-133843D01*
X813022Y-134426D01*
X814550Y-134134D01*
X815861Y-133260D01*
X816734Y-132093D01*
G01X825719Y-139676D02*
X827029Y-140259D01*
X828776Y-139676D01*
X829867Y-138510D01*
X830741Y-137051D01*
X832050Y-132385D01*
X834889Y-122760D01*
G01X827902D02*
X832050Y-132385D01*
G01X844529Y-126551D02*
X851516D01*
X850861Y-124509D01*
X849769Y-123343D01*
X848241Y-122760D01*
X846712Y-123051D01*
X845402Y-123926D01*
X844529Y-125968D01*
X844092Y-127718D01*
Y-129468D01*
X844529Y-131218D01*
X845621Y-132968D01*
X846931Y-134134D01*
X848459Y-134426D01*
X849987Y-133843D01*
X851516Y-132093D01*
G01X862247Y-134426D02*
Y-122760D01*
G01Y-125093D02*
X863339Y-123926D01*
X864431Y-123051D01*
X865959Y-122760D01*
X867050Y-123051D01*
X868361Y-123926D01*
G01X879529Y-132385D02*
X880621Y-133551D01*
X882149Y-134426D01*
X883459D01*
X884769Y-133843D01*
X885642Y-132968D01*
X886079Y-131802D01*
X885861Y-130051D01*
X884987Y-129176D01*
X881057Y-127426D01*
X880184Y-125384D01*
X880621Y-123926D01*
X881494Y-123051D01*
X882804Y-122760D01*
X884114Y-123051D01*
X885424Y-123926D01*
G01X924737Y-175926D02*
X925829Y-177676D01*
X927139Y-178843D01*
X928667Y-179426D01*
X930414Y-178843D01*
X931724Y-177676D01*
X933034Y-175926D01*
X933471Y-173593D01*
Y-161926D01*
G01X946604Y-179426D02*
X944857Y-179134D01*
X943329Y-177968D01*
X942019Y-176218D01*
X941145Y-174176D01*
X940709Y-171843D01*
Y-169509D01*
X941145Y-167176D01*
X942019Y-165134D01*
X943329Y-163385D01*
X944857Y-162218D01*
X946604Y-161926D01*
X948350Y-162218D01*
X949879Y-163385D01*
X951189Y-165134D01*
X952063Y-167176D01*
X952499Y-169509D01*
Y-171843D01*
X952063Y-174176D01*
X951189Y-176218D01*
X949879Y-177968D01*
X948350Y-179134D01*
X946604Y-179426D01*
G01X959519Y-177093D02*
X961266Y-178551D01*
X963231Y-179426D01*
X964977D01*
X966724Y-178551D01*
X968034Y-177093D01*
X968689Y-175051D01*
X968252Y-173010D01*
X967161Y-171259D01*
X965196Y-170093D01*
X962576Y-169509D01*
X961047Y-168343D01*
X960392Y-166301D01*
X960829Y-164259D01*
X961921Y-162801D01*
X963449Y-161926D01*
X964977D01*
X966506Y-162509D01*
X967816Y-163968D01*
G01X985971Y-179426D02*
X977237D01*
Y-161926D01*
X985971D01*
G01X982477Y-170384D02*
X977237D01*
G01X994737Y-179426D02*
Y-161926D01*
X999977D01*
X1001724Y-162801D01*
X1003034Y-164843D01*
X1003471Y-167176D01*
X1003034Y-169509D01*
X1001942Y-171259D01*
X999977Y-172135D01*
X994737D01*
G01X1012019Y-179426D02*
Y-161926D01*
G01X1021189D02*
Y-179426D01*
G01Y-170676D02*
X1012019D01*
G01X1047237Y-161926D02*
Y-179426D01*
X1055971D01*
G01X1063645D02*
X1069104Y-161926D01*
X1074563Y-179426D01*
G01X1072597Y-173301D02*
X1065610D01*
G01X1081801Y-161926D02*
Y-174468D01*
X1082674Y-177093D01*
X1084421Y-178843D01*
X1086604Y-179426D01*
X1088787Y-178843D01*
X1090534Y-177093D01*
X1091407Y-174468D01*
Y-161926D01*
G01X941801Y-134426D02*
Y-116926D01*
X946167D01*
X947914Y-117801D01*
X949224Y-118968D01*
X950316Y-120717D01*
X951189Y-122760D01*
X951407Y-125676D01*
X951189Y-128593D01*
X950316Y-130635D01*
X949224Y-132385D01*
X947914Y-133551D01*
X946167Y-134426D01*
X941801D01*
G01X960829Y-126551D02*
X967816D01*
X967161Y-124509D01*
X966069Y-123343D01*
X964541Y-122760D01*
X963012Y-123051D01*
X961702Y-123926D01*
X960829Y-125968D01*
X960392Y-127718D01*
Y-129468D01*
X960829Y-131218D01*
X961921Y-132968D01*
X963231Y-134134D01*
X964759Y-134426D01*
X966287Y-133843D01*
X967816Y-132093D01*
G01X978329Y-132385D02*
X979421Y-133551D01*
X980949Y-134426D01*
X982259D01*
X983569Y-133843D01*
X984442Y-132968D01*
X984879Y-131802D01*
X984661Y-130051D01*
X983787Y-129176D01*
X979857Y-127426D01*
X978984Y-125384D01*
X979421Y-123926D01*
X980294Y-123051D01*
X981604Y-122760D01*
X982914Y-123051D01*
X984224Y-123926D01*
G01X999104Y-122760D02*
Y-134426D01*
G01Y-118093D02*
X998667Y-117801D01*
Y-117218D01*
X999104Y-116926D01*
X999541Y-117218D01*
Y-117801D01*
X999104Y-118093D01*
G01X1013547Y-138801D02*
X1015076Y-139968D01*
X1016822Y-140259D01*
X1018350Y-139968D01*
X1019661Y-138510D01*
X1020534Y-136468D01*
Y-122760D01*
G01Y-125093D02*
X1019661Y-123926D01*
X1018350Y-123051D01*
X1016822Y-122760D01*
X1015076Y-123343D01*
X1013984Y-124509D01*
X1013110Y-126551D01*
X1012674Y-128593D01*
X1012892Y-130343D01*
X1013766Y-132385D01*
X1015076Y-133843D01*
X1016822Y-134426D01*
X1018132Y-134134D01*
X1019661Y-132968D01*
X1020534Y-131802D01*
G01X1030392Y-134426D02*
Y-122760D01*
G01Y-125676D02*
X1031266Y-124218D01*
X1032576Y-123051D01*
X1034322Y-122760D01*
X1035850Y-123051D01*
X1037161Y-124218D01*
X1037816Y-126259D01*
Y-134426D01*
G01X1048329Y-126551D02*
X1055316D01*
X1054661Y-124509D01*
X1053569Y-123343D01*
X1052041Y-122760D01*
X1050512Y-123051D01*
X1049202Y-123926D01*
X1048329Y-125968D01*
X1047892Y-127718D01*
Y-129468D01*
X1048329Y-131218D01*
X1049421Y-132968D01*
X1050731Y-134134D01*
X1052259Y-134426D01*
X1053787Y-133843D01*
X1055316Y-132093D01*
G01X1066047Y-134426D02*
Y-122760D01*
G01Y-125093D02*
X1067139Y-123926D01*
X1068231Y-123051D01*
X1069759Y-122760D01*
X1070850Y-123051D01*
X1072161Y-123926D01*
G01X1112804Y-179426D02*
Y-161926D01*
X1110184Y-165426D01*
G01Y-179426D02*
X1115424D01*
G01X1130304D02*
Y-161926D01*
X1127684Y-165426D01*
G01Y-179426D02*
X1132924D01*
G01X1143874Y-180009D02*
X1151734Y-161926D01*
G01X1161156Y-164843D02*
X1162466Y-163093D01*
X1163994Y-162218D01*
X1165741Y-161926D01*
X1167924Y-162509D01*
X1169452Y-163968D01*
X1169889Y-165717D01*
X1169671Y-167468D01*
X1168797Y-168926D01*
X1164431Y-171843D01*
X1162466Y-173884D01*
X1161156Y-176802D01*
X1160719Y-179426D01*
X1169889D01*
G01X1178001Y-176802D02*
X1179310Y-178260D01*
X1180839Y-179134D01*
X1182804Y-179426D01*
X1184769Y-178843D01*
X1186297Y-177676D01*
X1187389Y-175635D01*
X1187607Y-173301D01*
X1187171Y-170968D01*
X1186079Y-169509D01*
X1184550Y-168343D01*
X1183022Y-168051D01*
X1181494Y-168343D01*
X1179529Y-169509D01*
X1180184Y-161926D01*
X1186079D01*
G01X1196374Y-180009D02*
X1204234Y-161926D01*
G01X1213656Y-164843D02*
X1214966Y-163093D01*
X1216494Y-162218D01*
X1218241Y-161926D01*
X1220424Y-162509D01*
X1221952Y-163968D01*
X1222389Y-165717D01*
X1222171Y-167468D01*
X1221297Y-168926D01*
X1216931Y-171843D01*
X1214966Y-173884D01*
X1213656Y-176802D01*
X1213219Y-179426D01*
X1222389D01*
G01X1235304Y-161926D02*
X1233557Y-162509D01*
X1232247Y-163968D01*
X1231374Y-165717D01*
X1230719Y-168051D01*
X1230501Y-170676D01*
X1230719Y-173301D01*
X1231374Y-175635D01*
X1232247Y-177385D01*
X1233557Y-178843D01*
X1235304Y-179426D01*
X1237050Y-178843D01*
X1238361Y-177385D01*
X1239234Y-175635D01*
X1239889Y-173301D01*
X1240107Y-170676D01*
X1239889Y-168051D01*
X1239234Y-165717D01*
X1238361Y-163968D01*
X1237050Y-162509D01*
X1235304Y-161926D01*
G01X1252804Y-179426D02*
Y-161926D01*
X1250184Y-165426D01*
G01Y-179426D02*
X1255424D01*
G01X1272924D02*
Y-161926D01*
X1264845Y-174468D01*
X1275763D01*
G01X1160501Y-134426D02*
Y-116926D01*
X1164867D01*
X1166614Y-117801D01*
X1167924Y-118968D01*
X1169016Y-120717D01*
X1169889Y-122760D01*
X1170107Y-125676D01*
X1169889Y-128593D01*
X1169016Y-130635D01*
X1167924Y-132385D01*
X1166614Y-133551D01*
X1164867Y-134426D01*
X1160501D01*
G01X1186734D02*
Y-122760D01*
G01Y-124801D02*
X1185861Y-123635D01*
X1184550Y-123051D01*
X1183022Y-122760D01*
X1181494Y-123343D01*
X1180184Y-124509D01*
X1179310Y-126259D01*
X1178874Y-128593D01*
X1179310Y-130926D01*
X1180184Y-132676D01*
X1181494Y-133843D01*
X1183022Y-134426D01*
X1184550Y-134134D01*
X1185861Y-133260D01*
X1186734Y-132093D01*
G01X1200304Y-116926D02*
Y-134426D01*
G01X1197247Y-122760D02*
X1203361D01*
G01X1214529Y-126551D02*
X1221516D01*
X1220861Y-124509D01*
X1219769Y-123343D01*
X1218241Y-122760D01*
X1216712Y-123051D01*
X1215402Y-123926D01*
X1214529Y-125968D01*
X1214092Y-127718D01*
Y-129468D01*
X1214529Y-131218D01*
X1215621Y-132968D01*
X1216931Y-134134D01*
X1218459Y-134426D01*
X1219987Y-133843D01*
X1221516Y-132093D01*
G54D26*
X51094Y387325D03*
X60052Y387292D03*
X55352Y387374D03*
X43159Y373885D03*
X43072Y365847D03*
X538000Y293300D03*
X548000Y429300D03*
G54D35*
X421500Y192300D03*
Y180700D03*
X435000Y192300D03*
Y180700D03*
X448500Y192300D03*
Y180700D03*
X462000Y192300D03*
Y180700D03*
G54D17*
X38128Y374332D03*
X45807Y388068D03*
X542500Y269171D03*
X634488Y72003D03*
G54D27*
X38598Y333436D03*
Y337936D03*
X33508Y368932D03*
Y374132D03*
X69498Y369470D03*
X69547Y373979D03*
X69550Y378236D03*
X537733Y268971D03*
Y263971D03*
X533636Y322102D03*
X533536Y330602D03*
X533636Y326402D03*
X526200Y326000D03*
G54D36*
X487625Y198086D03*
Y173286D03*
X512989Y198162D03*
Y173362D03*
X538135Y198177D03*
Y173377D03*
G54D18*
X38109Y368733D03*
X542500Y263771D03*
X618000Y77300D03*
X617798Y408736D03*
X612798Y408636D03*
G54D19*
X41309Y387463D03*
G54D28*
X52705Y355795D03*
X48325Y355850D03*
X57398Y355860D03*
G54D37*
X570709Y161889D03*
X580709D03*
X570709Y214409D03*
X580709D03*
X570709Y204409D03*
X580709D03*
X570709Y191889D03*
X580709D03*
X570709Y181889D03*
X580709D03*
X570709Y171889D03*
X580709D03*
X570709Y244409D03*
X580709D03*
X570709Y276929D03*
X580709D03*
X570709Y266929D03*
X580709D03*
X570709Y256929D03*
X580709D03*
X570709Y234409D03*
X580709D03*
X570709Y224409D03*
X580709D03*
X570709Y286929D03*
X580709D03*
X590709Y161889D03*
X600709D03*
X590709Y214409D03*
X600709D03*
X590709Y204409D03*
X600709D03*
X590709Y191889D03*
X600709D03*
X590709Y181889D03*
X600709D03*
X590709Y171889D03*
X600709D03*
X590709Y244409D03*
X600709D03*
X590709Y276929D03*
X600709D03*
X590709Y266929D03*
X600709D03*
X590709Y256929D03*
X600709D03*
X590709Y234409D03*
X600709D03*
X590709Y224409D03*
X600709D03*
X590709Y286929D03*
X600709D03*
G54D38*
X529036Y308352D03*
X525161Y315852D03*
X532911D03*
X529011Y293257D03*
X532886Y300757D03*
X525136D03*
G54D29*
X43038Y353675D03*
X28182Y364061D03*
Y379003D03*
X43072Y360525D03*
X43159Y382607D03*
X74803Y369471D03*
X81000Y372786D03*
X66041Y359891D03*
X66100Y383508D03*
X135063Y304219D03*
X176762Y319444D03*
X228716Y315094D03*
X196289Y302044D03*
X264680Y317269D03*
X310990Y310744D03*
X358093Y312919D03*
X401561Y306394D03*
X463259Y299869D03*
X439407Y308569D03*
X439585Y321619D03*
X548417Y269770D03*
Y262970D03*
X540736Y309902D03*
X524888Y330228D03*
X537936Y322102D03*
X526270Y338185D03*
X529000Y353500D03*
X623500Y71500D03*
X622598Y331736D03*
X624898Y400936D03*
G54D39*
X559489Y427559D03*
X603780Y442126D03*
M02*
